# T6G (Grand Teton) — schematic netlist excerpt (pin names and nets, part order shuffled) for the footprints in the layout excerpt that follows; sources: Cadence DE-HDL packaged netlist, KiCad conversion of 04192023_DAF0TMB3IC0_F0TG_MB_C_brd_V02_OCP.brd

R3162  Q_RES  4.7K 1% CHIP  pkg 0402LF  page 137 : A = P3V3_OCP_V3_2 ; B = OCP_V3_2_ID0
C676  Q_CAP  1UF 4V 20% X6S  pkg 0201  page 301 : A = P1V8_CPU0_RT2_1A_1D ; B = GND
R6062  Q_RES  4.7K 5% EMPTY  pkg 0402LF  page 83 : A = P3V3_OCP_V3_2_EN_R ; B = P3V3_AUX

(kicad_pcb
	(version 20260206)
	(generator "pcbnew")
	(generator_version "10.0")
	(general
		(thickness 1.6)
		(legacy_teardrops no)
	)
	(paper "A4")
	(title_block
		(title "04192023_DAF0TMB3IC0_F0TG_MB_C_brd_V02_OCP.brd")
		(comment 1 "Grand Teton / footprints 7289-7291 of 8354")
	)
	(layers
		(0 "F.Cu" signal "TOP")
		(4 "In1.Cu" signal "GND")
		(6 "In2.Cu" signal "IN1")
		(8 "In3.Cu" signal "GND1")
		(10 "In4.Cu" signal "IN2")
		(12 "In5.Cu" signal "GND2")
		(14 "In6.Cu" signal "IN3")
		(16 "In7.Cu" signal "GND3")
		(18 "In8.Cu" signal "VCC")
		(20 "In9.Cu" signal "VCC1")
		(22 "In10.Cu" signal "GND4")
		(24 "In11.Cu" signal "IN4")
		(26 "In12.Cu" signal "GND5")
		(28 "In13.Cu" signal "IN5")
		(30 "In14.Cu" signal "GND6")
		(32 "In15.Cu" signal "IN6")
		(34 "In16.Cu" signal "GND7")
		(2 "B.Cu" signal "BOTTOM")
		(9 "F.Adhes" user "F.Adhesive")
		(11 "B.Adhes" user "B.Adhesive")
		(13 "F.Paste" user "Package Geometry/Pastemask Top")
		(15 "B.Paste" user "Package Geometry/Pastemask Bottom")
		(5 "F.SilkS" user "Ref Des/Silkscreen Top")
		(7 "B.SilkS" user "Ref Des/Silkscreen Bottom")
		(1 "F.Mask" user "Board Geometry/Soldermask Top")
		(3 "B.Mask" user "Board Geometry/Soldermask Bottom")
		(17 "Dwgs.User" user "User.Drawings")
		(19 "Cmts.User" user "User.Comments")
		(21 "Eco1.User" user "User.Eco1")
		(23 "Eco2.User" user "User.Eco2")
		(25 "Edge.Cuts" user "Board Geometry/Outline")
		(27 "Margin" user)
		(31 "F.CrtYd" user "Package Geometry/Place Bound Top")
		(29 "B.CrtYd" user "Package Geometry/Place Bound Bottom")
		(35 "F.Fab" user "Ref Des/Assembly Top")
		(33 "B.Fab" user "Ref Des/Assembly Bottom")
	)
	(footprint ""
		(layer "B.Cu")
		(at 71.809864 -11.26871 -90)
		(property "Reference" "R3162"
			(at 0 0 90)
			(layer "B.SilkS")
			(hide yes)
			(effects
				(font
					(size 1.27 1.27)
				)
				(justify mirror)
			)
		)
		(property "Value" ""
			(at 0 0 90)
			(layer "B.Fab")
			(effects
				(font
					(size 1.27 1.27)
				)
				(justify mirror)
			)
		)
		(duplicate_pad_numbers_are_jumpers no)
		(fp_line
			(start -0.7874 0.4064)
			(end 0.7874 0.4064)
			(stroke
				(width 0.1524)
				(type default)
			)
			(layer "B.SilkS")
		)
		(fp_line
			(start 0.7874 0.4064)
			(end 0.7874 -0.4064)
			(stroke
				(width 0.1524)
				(type default)
			)
			(layer "B.SilkS")
		)
		(fp_line
			(start -0.7874 -0.4064)
			(end -0.7874 0.4064)
			(stroke
				(width 0.1524)
				(type default)
			)
			(layer "B.SilkS")
		)
		(fp_line
			(start 0.7874 -0.4064)
			(end -0.7874 -0.4064)
			(stroke
				(width 0.1524)
				(type default)
			)
			(layer "B.SilkS")
		)
		(fp_line
			(start -0.67945 0.3048)
			(end -0.120396 0.3048)
			(stroke
				(width 0.1)
				(type default)
			)
			(layer "B.Fab")
		)
		(fp_line
			(start -0.120396 0.3048)
			(end -0.120396 0.2794)
			(stroke
				(width 0.1)
				(type default)
			)
			(layer "B.Fab")
		)
		(fp_line
			(start 0.12065 0.3048)
			(end 0.67945 0.3048)
			(stroke
				(width 0.1)
				(type default)
			)
			(layer "B.Fab")
		)
		(fp_line
			(start 0.67945 0.3048)
			(end 0.67945 -0.305054)
			(stroke
				(width 0.1)
				(type default)
			)
			(layer "B.Fab")
		)
		(fp_line
			(start -0.120396 0.2794)
			(end 0.12065 0.2794)
			(stroke
				(width 0.1)
				(type default)
			)
			(layer "B.Fab")
		)
		(fp_line
			(start 0.12065 0.2794)
			(end 0.12065 0.3048)
			(stroke
				(width 0.1)
				(type default)
			)
			(layer "B.Fab")
		)
		(fp_line
			(start -0.12065 -0.2794)
			(end -0.12065 -0.3048)
			(stroke
				(width 0.1)
				(type default)
			)
			(layer "B.Fab")
		)
		(fp_line
			(start 0.12065 -0.2794)
			(end -0.12065 -0.2794)
			(stroke
				(width 0.1)
				(type default)
			)
			(layer "B.Fab")
		)
		(fp_line
			(start -0.67945 -0.3048)
			(end -0.67945 0.3048)
			(stroke
				(width 0.1)
				(type default)
			)
			(layer "B.Fab")
		)
		(fp_line
			(start -0.12065 -0.3048)
			(end -0.67945 -0.3048)
			(stroke
				(width 0.1)
				(type default)
			)
			(layer "B.Fab")
		)
		(fp_line
			(start 0.12065 -0.305054)
			(end 0.12065 -0.2794)
			(stroke
				(width 0.1)
				(type default)
			)
			(layer "B.Fab")
		)
		(fp_line
			(start 0.67945 -0.305054)
			(end 0.12065 -0.305054)
			(stroke
				(width 0.1)
				(type default)
			)
			(layer "B.Fab")
		)
		(pad "1" smd circle
			(at 0.40005 0 90)
			(size 0 0)
			(layers "B.Cu" "B.Mask" "B.Paste")
			(net "P3V3_OCP_V3_2")
		)
		(pad "2" smd circle
			(at -0.40005 0 90)
			(size 0 0)
			(layers "B.Cu" "B.Mask" "B.Paste")
			(net "OCP_V3_2_ID0")
		)
	)
	(footprint ""
		(layer "B.Cu")
		(at 194.945 -97.119948 90)
		(property "Reference" "R6062"
			(at 0 0 90)
			(layer "B.SilkS")
			(hide yes)
			(effects
				(font
					(size 1.27 1.27)
				)
				(justify mirror)
			)
		)
		(property "Value" ""
			(at 0 0 90)
			(layer "B.Fab")
			(effects
				(font
					(size 1.27 1.27)
				)
				(justify mirror)
			)
		)
		(duplicate_pad_numbers_are_jumpers no)
		(fp_line
			(start 0.7874 -0.4064)
			(end -0.7874 -0.4064)
			(stroke
				(width 0.1524)
				(type default)
			)
			(layer "B.SilkS")
		)
		(fp_line
			(start -0.7874 -0.4064)
			(end -0.7874 0.4064)
			(stroke
				(width 0.1524)
				(type default)
			)
			(layer "B.SilkS")
		)
		(fp_line
			(start 0.7874 0.4064)
			(end 0.7874 -0.4064)
			(stroke
				(width 0.1524)
				(type default)
			)
			(layer "B.SilkS")
		)
		(fp_line
			(start -0.7874 0.4064)
			(end 0.7874 0.4064)
			(stroke
				(width 0.1524)
				(type default)
			)
			(layer "B.SilkS")
		)
		(fp_line
			(start 0.67945 -0.305054)
			(end 0.12065 -0.305054)
			(stroke
				(width 0.1)
				(type default)
			)
			(layer "B.Fab")
		)
		(fp_line
			(start 0.12065 -0.305054)
			(end 0.12065 -0.2794)
			(stroke
				(width 0.1)
				(type default)
			)
			(layer "B.Fab")
		)
		(fp_line
			(start -0.12065 -0.3048)
			(end -0.67945 -0.3048)
			(stroke
				(width 0.1)
				(type default)
			)
			(layer "B.Fab")
		)
		(fp_line
			(start -0.67945 -0.3048)
			(end -0.67945 0.3048)
			(stroke
				(width 0.1)
				(type default)
			)
			(layer "B.Fab")
		)
		(fp_line
			(start 0.12065 -0.2794)
			(end -0.12065 -0.2794)
			(stroke
				(width 0.1)
				(type default)
			)
			(layer "B.Fab")
		)
		(fp_line
			(start -0.12065 -0.2794)
			(end -0.12065 -0.3048)
			(stroke
				(width 0.1)
				(type default)
			)
			(layer "B.Fab")
		)
		(fp_line
			(start 0.12065 0.2794)
			(end 0.12065 0.3048)
			(stroke
				(width 0.1)
				(type default)
			)
			(layer "B.Fab")
		)
		(fp_line
			(start -0.120396 0.2794)
			(end 0.12065 0.2794)
			(stroke
				(width 0.1)
				(type default)
			)
			(layer "B.Fab")
		)
		(fp_line
			(start 0.67945 0.3048)
			(end 0.67945 -0.305054)
			(stroke
				(width 0.1)
				(type default)
			)
			(layer "B.Fab")
		)
		(fp_line
			(start 0.12065 0.3048)
			(end 0.67945 0.3048)
			(stroke
				(width 0.1)
				(type default)
			)
			(layer "B.Fab")
		)
		(fp_line
			(start -0.120396 0.3048)
			(end -0.120396 0.2794)
			(stroke
				(width 0.1)
				(type default)
			)
			(layer "B.Fab")
		)
		(fp_line
			(start -0.67945 0.3048)
			(end -0.120396 0.3048)
			(stroke
				(width 0.1)
				(type default)
			)
			(layer "B.Fab")
		)
		(pad "1" smd circle
			(at 0.40005 0 270)
			(size 0 0)
			(layers "B.Cu" "B.Mask" "B.Paste")
			(net "P3V3_OCP_V3_2_EN_R")
		)
		(pad "2" smd circle
			(at -0.40005 0 270)
			(size 0 0)
			(layers "B.Cu" "B.Mask" "B.Paste")
			(net "P3V3_AUX")
		)
	)
	(footprint ""
		(layer "B.Cu")
		(at 413.806132 -395.148562 90)
		(property "Reference" "C676"
			(at 0 0 90)
			(layer "B.SilkS")
			(hide yes)
			(effects
				(font
					(size 1.27 1.27)
				)
				(justify mirror)
			)
		)
		(property "Value" ""
			(at 0 0 90)
			(layer "B.Fab")
			(effects
				(font
					(size 1.27 1.27)
				)
				(justify mirror)
			)
		)
		(duplicate_pad_numbers_are_jumpers no)
		(fp_line
			(start 0.299974 -0.150114)
			(end -0.299974 -0.150114)
			(stroke
				(width 0.1)
				(type default)
			)
			(layer "B.Fab")
		)
		(fp_line
			(start -0.299974 -0.150114)
			(end -0.299974 0.150114)
			(stroke
				(width 0.1)
				(type default)
			)
			(layer "B.Fab")
		)
		(fp_line
			(start 0.299974 0.150114)
			(end 0.299974 -0.150114)
			(stroke
				(width 0.1)
				(type default)
			)
			(layer "B.Fab")
		)
		(fp_line
			(start -0.299974 0.150114)
			(end 0.299974 0.150114)
			(stroke
				(width 0.1)
				(type default)
			)
			(layer "B.Fab")
		)
		(pad "1" smd rect
			(at 0.2667 0 270)
			(size 0.3048 0.381)
			(layers "B.Cu" "B.Mask" "B.Paste")
			(net "P1V8_CPU0_RT2_1A_1D")
		)
		(pad "2" smd rect
			(at -0.2667 0 270)
			(size 0.3048 0.381)
			(layers "B.Cu" "B.Mask" "B.Paste")
			(net "GND")
		)
	)
)
